# BASEBOARD_FAB2 (Tioga Pass) — schematic netlist excerpt (pin names and nets, part order shuffled) for the footprints in the layout excerpt that follows; sources: Cadence DE-HDL packaged netlist, KiCad conversion of Wiwynn_Tioga_Pass_MB.brd

R9G3  RES  75 1.0% CHIP  pkg 0402  page 141 : A = LED_LAN_0_R_N ; B = LED_LAN_0_N
C3L18  CAPP  470UF 2V 20% ALUM  pkg SM  page 236 : A = PVNN_PCH_STBY ; B = GND
C2L32  CAP  47UF 4V 20% X6S  pkg 0805  page 237 : A = P1V8_PCH_STBY ; B = GND

(kicad_pcb
	(version 20260206)
	(generator "pcbnew")
	(generator_version "10.0")
	(general
		(thickness 1.6)
		(legacy_teardrops no)
	)
	(paper "A4")
	(title_block
		(title "Wiwynn_Tioga_Pass_MB.brd")
		(comment 1 "Tioga Pass / footprints 3584-3586 of 4770")
	)
	(layers
		(0 "F.Cu" signal "TOP")
		(4 "In1.Cu" signal "L2GND")
		(6 "In2.Cu" signal "L3")
		(8 "In3.Cu" signal "L4GND")
		(10 "In4.Cu" signal "L5")
		(12 "In5.Cu" signal "L6GND")
		(14 "In6.Cu" signal "L7VCC")
		(16 "In7.Cu" signal "L8VCC")
		(18 "In8.Cu" signal "L9GND")
		(20 "In9.Cu" signal "L10")
		(22 "In10.Cu" signal "L11GND")
		(24 "In11.Cu" signal "L12")
		(26 "In12.Cu" signal "L13GND")
		(2 "B.Cu" signal "BOTTOM")
		(9 "F.Adhes" user "F.Adhesive")
		(11 "B.Adhes" user "B.Adhesive")
		(13 "F.Paste" user "Package Geometry/Pastemask Top")
		(15 "B.Paste" user "Package Geometry/Pastemask Bottom")
		(5 "F.SilkS" user "Ref Des/Silkscreen Top")
		(7 "B.SilkS" user "Ref Des/Silkscreen Bottom")
		(1 "F.Mask" user "Board Geometry/Soldermask Top")
		(3 "B.Mask" user "Board Geometry/Soldermask Bottom")
		(17 "Dwgs.User" user "User.Drawings")
		(19 "Cmts.User" user "User.Comments")
		(21 "Eco1.User" user "User.Eco1")
		(23 "Eco2.User" user "User.Eco2")
		(25 "Edge.Cuts" user "Board Geometry/Outline")
		(27 "Margin" user)
		(31 "F.CrtYd" user "Package Geometry/Place Bound Top")
		(29 "B.CrtYd" user "Package Geometry/Place Bound Bottom")
		(35 "F.Fab" user "Ref Des/Assembly Top")
		(33 "B.Fab" user "Ref Des/Assembly Bottom")
	)
	(footprint ""
		(layer "B.Cu")
		(at 368.7064 -141.0462 180)
		(property "Reference" "C3L18"
			(at -3.10007 3.24612 270)
			(unlocked yes)
			(layer "B.SilkS")
			(effects
				(font
					(size 0.7874 0.5842)
					(thickness 0.1524)
				)
				(justify mirror)
			)
		)
		(property "Value" ""
			(at 0 0 0)
			(layer "B.Fab")
			(effects
				(font
					(size 1.27 1.27)
				)
				(justify mirror)
			)
		)
		(duplicate_pad_numbers_are_jumpers no)
		(fp_line
			(start 2.563114 1.633728)
			(end 1.6002 1.633728)
			(stroke
				(width 0.1524)
				(type default)
			)
			(layer "B.SilkS")
		)
		(fp_line
			(start 2.563114 -1.616456)
			(end 2.563114 1.633728)
			(stroke
				(width 0.1524)
				(type default)
			)
			(layer "B.SilkS")
		)
		(fp_line
			(start 2.286 7.366)
			(end 2.286 1.632712)
			(stroke
				(width 0.1524)
				(type default)
			)
			(layer "B.SilkS")
		)
		(fp_line
			(start 2.286 7.366)
			(end 1.60147 7.366)
			(stroke
				(width 0.1524)
				(type default)
			)
			(layer "B.SilkS")
		)
		(fp_line
			(start 1.6002 -1.616456)
			(end 2.563114 -1.616456)
			(stroke
				(width 0.1524)
				(type default)
			)
			(layer "B.SilkS")
		)
		(fp_line
			(start -1.6002 -1.616456)
			(end -2.504948 -1.616456)
			(stroke
				(width 0.1524)
				(type default)
			)
			(layer "B.SilkS")
		)
		(fp_line
			(start -2.286 7.366)
			(end -1.600708 7.366)
			(stroke
				(width 0.1524)
				(type default)
			)
			(layer "B.SilkS")
		)
		(fp_line
			(start -2.286 7.366)
			(end -2.286 1.63195)
			(stroke
				(width 0.1524)
				(type default)
			)
			(layer "B.SilkS")
		)
		(fp_line
			(start -2.504948 1.633728)
			(end -1.6002 1.633728)
			(stroke
				(width 0.1524)
				(type default)
			)
			(layer "B.SilkS")
		)
		(fp_line
			(start -2.504948 -1.616456)
			(end -2.504948 1.633728)
			(stroke
				(width 0.1524)
				(type default)
			)
			(layer "B.SilkS")
		)
		(fp_rect
			(start 2.286 7.366)
			(end -2.286 -0.254)
			(stroke
				(width 0)
				(type default)
			)
			(fill no)
			(layer "B.CrtYd")
		)
		(fp_line
			(start 2.286 7.366)
			(end 2.286 -0.254)
			(stroke
				(width 0.1)
				(type default)
			)
			(layer "B.Fab")
		)
		(fp_line
			(start 2.286 -0.254)
			(end -2.286 -0.254)
			(stroke
				(width 0.1)
				(type default)
			)
			(layer "B.Fab")
		)
		(fp_line
			(start -2.286 7.366)
			(end 2.286 7.366)
			(stroke
				(width 0.1)
				(type default)
			)
			(layer "B.Fab")
		)
		(fp_line
			(start -2.286 -0.254)
			(end -2.286 7.366)
			(stroke
				(width 0.1)
				(type default)
			)
			(layer "B.Fab")
		)
		(pad "1" smd rect
			(at 0 0)
			(size 2.54 3.048)
			(layers "B.Cu" "B.Mask" "B.Paste")
			(net "PVNN_PCH_STBY")
		)
		(pad "2" smd rect
			(at 0 7.112)
			(size 2.54 3.048)
			(layers "B.Cu" "B.Mask" "B.Paste")
			(net "GND")
		)
	)
	(footprint ""
		(layer "B.Cu")
		(at 404.43658 -143.561816 -90)
		(property "Reference" "C2L32"
			(at 0 0 90)
			(layer "B.SilkS")
			(hide yes)
			(effects
				(font
					(size 1.27 1.27)
				)
				(justify mirror)
			)
		)
		(property "Value" ""
			(at 0 0 90)
			(layer "B.Fab")
			(effects
				(font
					(size 1.27 1.27)
				)
				(justify mirror)
			)
		)
		(duplicate_pad_numbers_are_jumpers no)
		(fp_poly
			(pts
				(xy 0.7239 -0.2159) (xy -0.7239 -0.2159) (xy -0.7239 1.9939) (xy 0.7239 1.9939)
			)
			(stroke
				(width 0)
				(type default)
			)
			(fill no)
			(layer "B.CrtYd")
		)
		(fp_line
			(start -0.7239 1.9939)
			(end -0.7239 -0.2159)
			(stroke
				(width 0.1)
				(type default)
			)
			(layer "B.Fab")
		)
		(fp_line
			(start 0.7239 1.9939)
			(end -0.7239 1.9939)
			(stroke
				(width 0.1)
				(type default)
			)
			(layer "B.Fab")
		)
		(fp_line
			(start -0.7239 -0.2159)
			(end 0.7239 -0.2159)
			(stroke
				(width 0.1)
				(type default)
			)
			(layer "B.Fab")
		)
		(fp_line
			(start 0.7239 -0.2159)
			(end 0.7239 1.9939)
			(stroke
				(width 0.1)
				(type default)
			)
			(layer "B.Fab")
		)
		(pad "1" smd rect
			(at 0 0 90)
			(size 1.27 1.016)
			(layers "B.Cu" "B.Mask" "B.Paste")
			(net "P1V8_PCH_STBY")
		)
		(pad "2" smd rect
			(at 0 1.778 90)
			(size 1.27 1.016)
			(layers "B.Cu" "B.Mask" "B.Paste")
			(net "GND")
		)
		(zone
			(layer "B.Cu")
			(hatch none 0.5)
			(connect_pads
				(clearance 0)
			)
			(min_thickness 0.25)
			(keepout
				(tracks not_allowed)
				(vias allowed)
				(pads allowed)
				(copperpour not_allowed)
				(footprints allowed)
			)
			(placement
				(enabled no)
				(sheetname "")
			)
			(fill
				(thermal_gap 0.5)
				(thermal_bridge_width 0.5)
				(island_removal_mode 0)
			)
			(polygon
				(pts
					(xy 403.92858 -142.926816) (xy 403.92858 -144.196816) (xy 403.16658 -144.196816) (xy 403.16658 -142.926816)
				)
			)
		)
	)
	(footprint ""
		(layer "B.Cu")
		(at 482.132894 -17.067022 90)
		(property "Reference" "R9G3"
			(at 0 0 90)
			(layer "B.SilkS")
			(hide yes)
			(effects
				(font
					(size 1.27 1.27)
				)
				(justify mirror)
			)
		)
		(property "Value" ""
			(at 0 0 90)
			(layer "B.Fab")
			(effects
				(font
					(size 1.27 1.27)
				)
				(justify mirror)
			)
		)
		(duplicate_pad_numbers_are_jumpers no)
		(fp_poly
			(pts
				(xy 0.2794 -0.1016) (xy -0.2794 -0.1016) (xy -0.2794 0.9906) (xy 0.2794 0.9906)
			)
			(stroke
				(width 0)
				(type default)
			)
			(fill no)
			(layer "B.CrtYd")
		)
		(fp_line
			(start 0.2794 -0.1016)
			(end 0.2794 0.9906)
			(stroke
				(width 0.1)
				(type default)
			)
			(layer "B.Fab")
		)
		(fp_line
			(start -0.2794 -0.1016)
			(end 0.2794 -0.1016)
			(stroke
				(width 0.1)
				(type default)
			)
			(layer "B.Fab")
		)
		(fp_line
			(start 0.2794 0.9906)
			(end -0.2794 0.9906)
			(stroke
				(width 0.1)
				(type default)
			)
			(layer "B.Fab")
		)
		(fp_line
			(start -0.2794 0.9906)
			(end -0.2794 -0.1016)
			(stroke
				(width 0.1)
				(type default)
			)
			(layer "B.Fab")
		)
		(pad "1" smd rect
			(at 0 0 270)
			(size 0.508 0.508)
			(layers "B.Cu" "B.Mask" "B.Paste")
			(net "LED_LAN_0_R_N")
		)
		(pad "2" smd rect
			(at 0 0.889 270)
			(size 0.508 0.508)
			(layers "B.Cu" "B.Mask" "B.Paste")
			(net "LED_LAN_0_N")
		)
		(zone
			(layer "B.Cu")
			(hatch none 0.5)
			(connect_pads
				(clearance 0)
			)
			(min_thickness 0.25)
			(keepout
				(tracks allowed)
				(vias not_allowed)
				(pads allowed)
				(copperpour not_allowed)
				(footprints allowed)
			)
			(placement
				(enabled no)
				(sheetname "")
			)
			(fill
				(thermal_gap 0.5)
				(thermal_bridge_width 0.5)
				(island_removal_mode 0)
			)
			(polygon
				(pts
					(xy 482.386894 -17.321022) (xy 482.386894 -16.813022) (xy 482.767894 -16.813022) (xy 482.767894 -17.321022)
				)
			)
		)
		(zone
			(layer "B.Cu")
			(hatch none 0.5)
			(connect_pads
				(clearance 0)
			)
			(min_thickness 0.25)
			(keepout
				(tracks not_allowed)
				(vias allowed)
				(pads allowed)
				(copperpour not_allowed)
				(footprints allowed)
			)
			(placement
				(enabled no)
				(sheetname "")
			)
			(fill
				(thermal_gap 0.5)
				(thermal_bridge_width 0.5)
				(island_removal_mode 0)
			)
			(polygon
				(pts
					(xy 482.767894 -17.321022) (xy 482.767894 -16.813022) (xy 482.386894 -16.813022) (xy 482.386894 -17.321022)
				)
			)
		)
	)
)
